# BASEBOARD_FAB2 (Tioga Pass) — schematic netlist excerpt (pin names and nets, part order shuffled) for the footprints in the layout excerpt that follows; sources: Cadence DE-HDL packaged netlist, KiCad conversion of Wiwynn_Tioga_Pass_MB.brd

C7F5  CAP  10UF 16V 10% X6S  pkg 0805  page 231 : A = VR_FET_SW_P12V_STBY_PVPP_ABC ; B = GND
C2G2  CAP_A  47UF 4V 20% X5R  pkg 0603V  page 225 : A = PVDDQ_GHJ ; B = GND
R9A13  RES  33.2 1% CHIP  pkg 0402  page 135 : A = FM_PCH_SATA_RAID_KEY_R ; B = FM_PCH_SATA_RAID_KEY

(kicad_pcb
	(version 20260206)
	(generator "pcbnew")
	(generator_version "10.0")
	(general
		(thickness 1.6)
		(legacy_teardrops no)
	)
	(paper "A4")
	(title_block
		(title "Wiwynn_Tioga_Pass_MB.brd")
		(comment 1 "Tioga Pass / footprints 611-613 of 4770")
	)
	(layers
		(0 "F.Cu" signal "TOP")
		(4 "In1.Cu" signal "L2GND")
		(6 "In2.Cu" signal "L3")
		(8 "In3.Cu" signal "L4GND")
		(10 "In4.Cu" signal "L5")
		(12 "In5.Cu" signal "L6GND")
		(14 "In6.Cu" signal "L7VCC")
		(16 "In7.Cu" signal "L8VCC")
		(18 "In8.Cu" signal "L9GND")
		(20 "In9.Cu" signal "L10")
		(22 "In10.Cu" signal "L11GND")
		(24 "In11.Cu" signal "L12")
		(26 "In12.Cu" signal "L13GND")
		(2 "B.Cu" signal "BOTTOM")
		(9 "F.Adhes" user "F.Adhesive")
		(11 "B.Adhes" user "B.Adhesive")
		(13 "F.Paste" user "Package Geometry/Pastemask Top")
		(15 "B.Paste" user "Package Geometry/Pastemask Bottom")
		(5 "F.SilkS" user "Ref Des/Silkscreen Top")
		(7 "B.SilkS" user "Ref Des/Silkscreen Bottom")
		(1 "F.Mask" user "Board Geometry/Soldermask Top")
		(3 "B.Mask" user "Board Geometry/Soldermask Bottom")
		(17 "Dwgs.User" user "User.Drawings")
		(19 "Cmts.User" user "User.Comments")
		(21 "Eco1.User" user "User.Eco1")
		(23 "Eco2.User" user "User.Eco2")
		(25 "Edge.Cuts" user "Board Geometry/Outline")
		(27 "Margin" user)
		(31 "F.CrtYd" user "Package Geometry/Place Bound Top")
		(29 "B.CrtYd" user "Package Geometry/Place Bound Bottom")
		(35 "F.Fab" user "Ref Des/Assembly Top")
		(33 "B.Fab" user "Ref Des/Assembly Bottom")
	)
	(footprint ""
		(layer "F.Cu")
		(at 83.856068 -12.954 -90)
		(property "Reference" "C2G2"
			(at 1.848866 0.752348 270)
			(unlocked yes)
			(layer "F.SilkS")
			(effects
				(font
					(size 1.27 0.9652)
					(thickness 0.1524)
				)
			)
		)
		(property "Value" ""
			(at 0 0 270)
			(layer "F.Fab")
			(effects
				(font
					(size 1.27 1.27)
				)
			)
		)
		(duplicate_pad_numbers_are_jumpers no)
		(fp_rect
			(start -0.500126 1.598422)
			(end 0.500126 -0.201422)
			(stroke
				(width 0)
				(type default)
			)
			(fill no)
			(layer "F.CrtYd")
		)
		(fp_line
			(start -0.500126 1.598422)
			(end -0.500126 -0.201422)
			(stroke
				(width 0.1)
				(type default)
			)
			(layer "F.Fab")
		)
		(fp_line
			(start 0.500126 1.598422)
			(end -0.500126 1.598422)
			(stroke
				(width 0.1)
				(type default)
			)
			(layer "F.Fab")
		)
		(fp_line
			(start -0.500126 -0.201422)
			(end 0.500126 -0.201422)
			(stroke
				(width 0.1)
				(type default)
			)
			(layer "F.Fab")
		)
		(fp_line
			(start 0.500126 -0.201422)
			(end 0.500126 1.598422)
			(stroke
				(width 0.1)
				(type default)
			)
			(layer "F.Fab")
		)
		(pad "1" smd rect
			(at 0 0 180)
			(size 0.889 0.9906)
			(layers "F.Cu" "F.Mask" "F.Paste")
			(net "PVDDQ_GHJ")
		)
		(pad "2" smd rect
			(at 0 1.397 180)
			(size 0.889 0.9906)
			(layers "F.Cu" "F.Mask" "F.Paste")
			(net "GND")
		)
		(zone
			(layer "F.Cu")
			(hatch none 0.5)
			(connect_pads
				(clearance 0)
			)
			(min_thickness 0.25)
			(keepout
				(tracks allowed)
				(vias not_allowed)
				(pads allowed)
				(copperpour not_allowed)
				(footprints allowed)
			)
			(placement
				(enabled no)
				(sheetname "")
			)
			(fill
				(thermal_gap 0.5)
				(thermal_bridge_width 0.5)
				(island_removal_mode 0)
			)
			(polygon
				(pts
					(xy 82.903568 -13.4493) (xy 82.903568 -12.4587) (xy 83.411568 -12.4587) (xy 83.411568 -13.4493)
				)
			)
		)
		(zone
			(layer "F.Cu")
			(hatch none 0.5)
			(connect_pads
				(clearance 0)
			)
			(min_thickness 0.25)
			(keepout
				(tracks not_allowed)
				(vias allowed)
				(pads allowed)
				(copperpour not_allowed)
				(footprints allowed)
			)
			(placement
				(enabled no)
				(sheetname "")
			)
			(fill
				(thermal_gap 0.5)
				(thermal_bridge_width 0.5)
				(island_removal_mode 0)
			)
			(polygon
				(pts
					(xy 82.903568 -13.4493) (xy 82.903568 -12.4587) (xy 83.411568 -12.4587) (xy 83.411568 -13.4493)
				)
			)
		)
	)
	(footprint ""
		(layer "F.Cu")
		(at 473.075 -146.7485)
		(property "Reference" "R9A13"
			(at 0 0 0)
			(layer "F.SilkS")
			(hide yes)
			(effects
				(font
					(size 1.27 1.27)
				)
			)
		)
		(property "Value" ""
			(at 0 0 0)
			(layer "F.Fab")
			(effects
				(font
					(size 1.27 1.27)
				)
			)
		)
		(duplicate_pad_numbers_are_jumpers no)
		(fp_poly
			(pts
				(xy -0.2794 -0.1016) (xy 0.2794 -0.1016) (xy 0.2794 0.9906) (xy -0.2794 0.9906)
			)
			(stroke
				(width 0)
				(type default)
			)
			(fill no)
			(layer "F.CrtYd")
		)
		(fp_line
			(start -0.2794 -0.1016)
			(end -0.2794 0.9906)
			(stroke
				(width 0.1)
				(type default)
			)
			(layer "F.Fab")
		)
		(fp_line
			(start -0.2794 0.9906)
			(end 0.2794 0.9906)
			(stroke
				(width 0.1)
				(type default)
			)
			(layer "F.Fab")
		)
		(fp_line
			(start 0.2794 -0.1016)
			(end -0.2794 -0.1016)
			(stroke
				(width 0.1)
				(type default)
			)
			(layer "F.Fab")
		)
		(fp_line
			(start 0.2794 0.9906)
			(end 0.2794 -0.1016)
			(stroke
				(width 0.1)
				(type default)
			)
			(layer "F.Fab")
		)
		(pad "1" smd rect
			(at 0 0)
			(size 0.508 0.508)
			(layers "F.Cu" "F.Mask" "F.Paste")
			(net "FM_PCH_SATA_RAID_KEY_R")
		)
		(pad "2" smd rect
			(at 0 0.889)
			(size 0.508 0.508)
			(layers "F.Cu" "F.Mask" "F.Paste")
			(net "FM_PCH_SATA_RAID_KEY")
		)
		(zone
			(layer "F.Cu")
			(hatch none 0.5)
			(connect_pads
				(clearance 0)
			)
			(min_thickness 0.25)
			(keepout
				(tracks allowed)
				(vias not_allowed)
				(pads allowed)
				(copperpour not_allowed)
				(footprints allowed)
			)
			(placement
				(enabled no)
				(sheetname "")
			)
			(fill
				(thermal_gap 0.5)
				(thermal_bridge_width 0.5)
				(island_removal_mode 0)
			)
			(polygon
				(pts
					(xy 472.821 -146.4945) (xy 473.329 -146.4945) (xy 473.329 -146.1135) (xy 472.821 -146.1135)
				)
			)
		)
		(zone
			(layer "F.Cu")
			(hatch none 0.5)
			(connect_pads
				(clearance 0)
			)
			(min_thickness 0.25)
			(keepout
				(tracks not_allowed)
				(vias allowed)
				(pads allowed)
				(copperpour not_allowed)
				(footprints allowed)
			)
			(placement
				(enabled no)
				(sheetname "")
			)
			(fill
				(thermal_gap 0.5)
				(thermal_bridge_width 0.5)
				(island_removal_mode 0)
			)
			(polygon
				(pts
					(xy 472.821 -146.1135) (xy 473.329 -146.1135) (xy 473.329 -146.4945) (xy 472.821 -146.4945)
				)
			)
		)
	)
	(footprint ""
		(layer "F.Cu")
		(at 351.028 -28.575 180)
		(property "Reference" "C7F5"
			(at 0 0 180)
			(layer "F.SilkS")
			(hide yes)
			(effects
				(font
					(size 1.27 1.27)
				)
			)
		)
		(property "Value" ""
			(at 0 0 180)
			(layer "F.Fab")
			(effects
				(font
					(size 1.27 1.27)
				)
			)
		)
		(duplicate_pad_numbers_are_jumpers no)
		(fp_poly
			(pts
				(xy -0.7239 -0.2159) (xy 0.7239 -0.2159) (xy 0.7239 1.9939) (xy -0.7239 1.9939)
			)
			(stroke
				(width 0)
				(type default)
			)
			(fill no)
			(layer "F.CrtYd")
		)
		(fp_line
			(start 0.7239 1.9939)
			(end 0.7239 -0.2159)
			(stroke
				(width 0.1)
				(type default)
			)
			(layer "F.Fab")
		)
		(fp_line
			(start 0.7239 -0.2159)
			(end -0.7239 -0.2159)
			(stroke
				(width 0.1)
				(type default)
			)
			(layer "F.Fab")
		)
		(fp_line
			(start -0.7239 1.9939)
			(end 0.7239 1.9939)
			(stroke
				(width 0.1)
				(type default)
			)
			(layer "F.Fab")
		)
		(fp_line
			(start -0.7239 -0.2159)
			(end -0.7239 1.9939)
			(stroke
				(width 0.1)
				(type default)
			)
			(layer "F.Fab")
		)
		(pad "1" smd rect
			(at 0 0 180)
			(size 1.27 1.016)
			(layers "F.Cu" "F.Mask" "F.Paste")
			(net "VR_FET_SW_P12V_STBY_PVPP_ABC")
		)
		(pad "2" smd rect
			(at 0 1.778 180)
			(size 1.27 1.016)
			(layers "F.Cu" "F.Mask" "F.Paste")
			(net "GND")
		)
		(zone
			(layer "F.Cu")
			(hatch none 0.5)
			(connect_pads
				(clearance 0)
			)
			(min_thickness 0.25)
			(keepout
				(tracks not_allowed)
				(vias allowed)
				(pads allowed)
				(copperpour not_allowed)
				(footprints allowed)
			)
			(placement
				(enabled no)
				(sheetname "")
			)
			(fill
				(thermal_gap 0.5)
				(thermal_bridge_width 0.5)
				(island_removal_mode 0)
			)
			(polygon
				(pts
					(xy 351.663 -29.083) (xy 350.393 -29.083) (xy 350.393 -29.845) (xy 351.663 -29.845)
				)
			)
		)
	)
)
